# TIMECARD (Time Appliance Project (Time Card)) — schematic netlist excerpt (pin names and nets, part order shuffled) for the footprints in the layout excerpt that follows; sources: Cadence DE-HDL packaged netlist, KiCad conversion of R4006-B0001-02_R01.brd

R41  RESISTOR  0OHM -  pkg SMC_0402R_H016  page 9 : \1\ = PCIE_CONN_TDI ; \2\ = FPGA_TDI
C24  CAPACITOR  0.1UF 10%  pkg SMC_0402R_H022  page 9 : \1\ = C_CPU_RX_PCIE_MGT0_TXP ; \2\ = CPU_RX_PCIE_MGT0_TXP

(kicad_pcb
	(version 20260206)
	(generator "pcbnew")
	(generator_version "10.0")
	(general
		(thickness 1.6)
		(legacy_teardrops no)
	)
	(paper "A4")
	(title_block
		(title "timecard-production-celestica-r4006 — R4006-B0001-02_R01.brd")
		(comment 1 "Time Appliance Project (Time Card) / footprints 685-686 of 1113")
	)
	(layers
		(0 "F.Cu" signal "TOP")
		(4 "In1.Cu" signal "L02_GND1")
		(6 "In2.Cu" signal "L03_SIG1")
		(8 "In3.Cu" signal "L04_GND2")
		(10 "In4.Cu" signal "L05_VCC1")
		(12 "In5.Cu" signal "L06_VCC2")
		(14 "In6.Cu" signal "L07_GND3")
		(16 "In7.Cu" signal "L08_SIG2")
		(18 "In8.Cu" signal "L09_GND4")
		(2 "B.Cu" signal "BOTTOM")
		(9 "F.Adhes" user "F.Adhesive")
		(11 "B.Adhes" user "B.Adhesive")
		(13 "F.Paste" user "Package Geometry/Pastemask Top")
		(15 "B.Paste" user "Package Geometry/Pastemask Bottom")
		(5 "F.SilkS" user "Ref Des/Silkscreen Top")
		(7 "B.SilkS" user "Ref Des/Silkscreen Bottom")
		(1 "F.Mask" user "Board Geometry/Soldermask Top")
		(3 "B.Mask" user "Board Geometry/Soldermask Bottom")
		(17 "Dwgs.User" user "User.Drawings")
		(19 "Cmts.User" user "User.Comments")
		(21 "Eco1.User" user "User.Eco1")
		(23 "Eco2.User" user "User.Eco2")
		(25 "Edge.Cuts" user "Board Geometry/Outline")
		(27 "Margin" user)
		(31 "F.CrtYd" user "Package Geometry/Place Bound Top")
		(29 "B.CrtYd" user "Package Geometry/Place Bound Bottom")
		(35 "F.Fab" user "Ref Des/Assembly Top")
		(33 "B.Fab" user "Ref Des/Assembly Bottom")
	)
	(footprint ""
		(layer "B.Cu")
		(at 140.335 -77.851)
		(property "Reference" "R41"
			(at 0.381 -2.11963 0)
			(unlocked yes)
			(layer "B.SilkS")
			(effects
				(font
					(size 0.7874 0.5842)
					(thickness 0.1524)
				)
				(justify mirror)
			)
		)
		(property "Value" "VAL*"
			(at -0.02032 2.13233 0)
			(unlocked yes)
			(layer "B.Fab")
			(hide yes)
			(effects
				(font
					(size 0.7874 0.5842)
					(thickness 0.1524)
				)
				(justify mirror)
			)
		)
		(property "Tolerance" "TOL*"
			(at -0.044704 3.05435 0)
			(unlocked yes)
			(layer "Cmts.User")
			(hide yes)
			(effects
				(font
					(size 0.7874 0.5842)
					(thickness 0.1524)
				)
				(justify mirror)
			)
		)
		(property "User Part Number" "PARTNUM*"
			(at -0.02032 4.024884 0)
			(unlocked yes)
			(layer "Cmts.User")
			(hide yes)
			(effects
				(font
					(size 0.7874 0.5842)
					(thickness 0.1524)
				)
				(justify mirror)
			)
		)
		(property "Device Type" "RESISTOR-G155-100R0-J0,0OHM,-"
			(at -0.008382 1.210564 0)
			(unlocked yes)
			(layer "B.Fab")
			(hide yes)
			(effects
				(font
					(size 0.7874 0.5842)
					(thickness 0.1524)
				)
				(justify mirror)
			)
		)
		(duplicate_pad_numbers_are_jumpers no)
		(fp_line
			(start -1.143 -0.5588)
			(end 1.143 -0.5588)
			(stroke
				(width 0.1)
				(type default)
			)
			(layer "B.SilkS")
		)
		(fp_line
			(start -1.143 0.5588)
			(end -1.143 -0.5588)
			(stroke
				(width 0.1)
				(type default)
			)
			(layer "B.SilkS")
		)
		(fp_line
			(start 1.143 -0.5588)
			(end 1.143 0.5588)
			(stroke
				(width 0.1)
				(type default)
			)
			(layer "B.SilkS")
		)
		(fp_line
			(start 1.143 0.5588)
			(end -1.143 0.5588)
			(stroke
				(width 0.1)
				(type default)
			)
			(layer "B.SilkS")
		)
		(fp_rect
			(start 1.143 0.5588)
			(end -1.143 -0.5588)
			(stroke
				(width 0)
				(type default)
			)
			(fill no)
			(layer "B.CrtYd")
		)
		(fp_line
			(start -0.508 -0.3048)
			(end 0.508 -0.3048)
			(stroke
				(width 0.1)
				(type default)
			)
			(layer "B.Fab")
		)
		(fp_line
			(start -0.508 0.3048)
			(end -0.508 -0.3048)
			(stroke
				(width 0.1)
				(type default)
			)
			(layer "B.Fab")
		)
		(fp_line
			(start 0.508 -0.3048)
			(end 0.508 0.3048)
			(stroke
				(width 0.1)
				(type default)
			)
			(layer "B.Fab")
		)
		(fp_line
			(start 0.508 0.3048)
			(end -0.508 0.3048)
			(stroke
				(width 0.1)
				(type default)
			)
			(layer "B.Fab")
		)
		(pad "1" smd rect
			(at 0.5334 0 180)
			(size 0.7112 0.6096)
			(layers "B.Cu" "B.Mask" "B.Paste")
			(net "PCIE_CONN_TDI")
		)
		(pad "2" smd rect
			(at -0.5334 0 180)
			(size 0.7112 0.6096)
			(layers "B.Cu" "B.Mask" "B.Paste")
			(net "FPGA_TDI")
		)
		(zone
			(layer "B.Cu")
			(hatch none 0.5)
			(connect_pads
				(clearance 0)
			)
			(min_thickness 0.25)
			(keepout
				(tracks allowed)
				(vias not_allowed)
				(pads allowed)
				(copperpour not_allowed)
				(footprints allowed)
			)
			(placement
				(enabled no)
				(sheetname "")
			)
			(fill
				(thermal_gap 0.5)
				(thermal_bridge_width 0.5)
				(island_removal_mode 0)
			)
			(polygon
				(pts
					(xy 140.4112 -77.5462) (xy 140.4112 -78.1558) (xy 140.2588 -78.1558) (xy 140.2588 -77.5462)
				)
			)
		)
	)
	(footprint ""
		(layer "B.Cu")
		(at 62.514988 -15.367 -90)
		(property "Reference" "C24"
			(at 2.032 0.062738 270)
			(unlocked yes)
			(layer "B.SilkS")
			(effects
				(font
					(size 0.635 0.4064)
					(thickness 0.1524)
				)
				(justify mirror)
			)
		)
		(property "Value" "VAL*"
			(at -0.0762 2.067306 270)
			(unlocked yes)
			(layer "B.Fab")
			(hide yes)
			(effects
				(font
					(size 0.7874 0.5842)
					(thickness 0.1524)
				)
				(justify mirror)
			)
		)
		(property "Tolerance" "TOL*"
			(at -0.0762 3.032506 270)
			(unlocked yes)
			(layer "Cmts.User")
			(hide yes)
			(effects
				(font
					(size 0.7874 0.5842)
					(thickness 0.1524)
				)
				(justify mirror)
			)
		)
		(property "User Part Number" "PARTNUM*"
			(at -0.1016 4.023106 270)
			(unlocked yes)
			(layer "Cmts.User")
			(hide yes)
			(effects
				(font
					(size 0.7874 0.5842)
					(thickness 0.1524)
				)
				(justify mirror)
			)
		)
		(property "Device Type" "CAPACITOR-G105-0B104-CK,0.1UF,A"
			(at -0.0508 1.127506 270)
			(unlocked yes)
			(layer "B.Fab")
			(hide yes)
			(effects
				(font
					(size 0.7874 0.5842)
					(thickness 0.1524)
				)
				(justify mirror)
			)
		)
		(duplicate_pad_numbers_are_jumpers no)
		(fp_line
			(start -1.143 0.5588)
			(end -1.143 -0.5588)
			(stroke
				(width 0.1)
				(type default)
			)
			(layer "B.SilkS")
		)
		(fp_line
			(start 1.143 0.5588)
			(end -1.143 0.5588)
			(stroke
				(width 0.1)
				(type default)
			)
			(layer "B.SilkS")
		)
		(fp_line
			(start -1.143 -0.5588)
			(end 1.143 -0.5588)
			(stroke
				(width 0.1)
				(type default)
			)
			(layer "B.SilkS")
		)
		(fp_line
			(start 1.143 -0.5588)
			(end 1.143 0.5588)
			(stroke
				(width 0.1)
				(type default)
			)
			(layer "B.SilkS")
		)
		(fp_rect
			(start 1.143 0.5588)
			(end -1.143 -0.5588)
			(stroke
				(width 0)
				(type default)
			)
			(fill no)
			(layer "B.CrtYd")
		)
		(fp_line
			(start -0.508 0.3048)
			(end -0.508 -0.3048)
			(stroke
				(width 0.1)
				(type default)
			)
			(layer "B.Fab")
		)
		(fp_line
			(start 0.508 0.3048)
			(end -0.508 0.3048)
			(stroke
				(width 0.1)
				(type default)
			)
			(layer "B.Fab")
		)
		(fp_line
			(start -0.508 -0.3048)
			(end 0.508 -0.3048)
			(stroke
				(width 0.1)
				(type default)
			)
			(layer "B.Fab")
		)
		(fp_line
			(start 0.508 -0.3048)
			(end 0.508 0.3048)
			(stroke
				(width 0.1)
				(type default)
			)
			(layer "B.Fab")
		)
		(pad "1" smd rect
			(at 0.5334 0 90)
			(size 0.7112 0.6096)
			(layers "B.Cu" "B.Mask" "B.Paste")
			(net "C_CPU_RX_PCIE_MGT0_TXP")
		)
		(pad "2" smd rect
			(at -0.5334 0 90)
			(size 0.7112 0.6096)
			(layers "B.Cu" "B.Mask" "B.Paste")
			(net "CPU_RX_PCIE_MGT0_TXP")
		)
		(zone
			(layer "B.Cu")
			(hatch none 0.5)
			(connect_pads
				(clearance 0)
			)
			(min_thickness 0.25)
			(keepout
				(tracks allowed)
				(vias not_allowed)
				(pads allowed)
				(copperpour not_allowed)
				(footprints allowed)
			)
			(placement
				(enabled no)
				(sheetname "")
			)
			(fill
				(thermal_gap 0.5)
				(thermal_bridge_width 0.5)
				(island_removal_mode 0)
			)
			(polygon
				(pts
					(xy 62.210188 -15.2908) (xy 62.819788 -15.2908) (xy 62.819788 -15.4432) (xy 62.210188 -15.4432)
				)
			)
		)
	)
)
